# T6G (Grand Teton) — schematic netlist excerpt (pin names and nets, part order shuffled) for the footprints in the layout excerpt that follows; sources: Cadence DE-HDL packaged netlist, KiCad conversion of 04192023_DAF0TMB3IC0_F0TG_MB_C_brd_V02_OCP.brd

PC253  Q_CAP  470PF 50V 10% X7R  pkg 0402  page 210 : A = PVDDCR_SOC_P1_TEMP1 ; B = GND

(kicad_pcb
	(version 20260206)
	(generator "pcbnew")
	(generator_version "10.0")
	(general
		(thickness 1.6)
		(legacy_teardrops no)
	)
	(paper "A4")
	(title_block
		(title "04192023_DAF0TMB3IC0_F0TG_MB_C_brd_V02_OCP.brd")
		(comment 1 "Grand Teton / footprints 6466-6466 of 8354")
	)
	(layers
		(0 "F.Cu" signal "TOP")
		(4 "In1.Cu" signal "GND")
		(6 "In2.Cu" signal "IN1")
		(8 "In3.Cu" signal "GND1")
		(10 "In4.Cu" signal "IN2")
		(12 "In5.Cu" signal "GND2")
		(14 "In6.Cu" signal "IN3")
		(16 "In7.Cu" signal "GND3")
		(18 "In8.Cu" signal "VCC")
		(20 "In9.Cu" signal "VCC1")
		(22 "In10.Cu" signal "GND4")
		(24 "In11.Cu" signal "IN4")
		(26 "In12.Cu" signal "GND5")
		(28 "In13.Cu" signal "IN5")
		(30 "In14.Cu" signal "GND6")
		(32 "In15.Cu" signal "IN6")
		(34 "In16.Cu" signal "GND7")
		(2 "B.Cu" signal "BOTTOM")
		(9 "F.Adhes" user "F.Adhesive")
		(11 "B.Adhes" user "B.Adhesive")
		(13 "F.Paste" user "Package Geometry/Pastemask Top")
		(15 "B.Paste" user "Package Geometry/Pastemask Bottom")
		(5 "F.SilkS" user "Ref Des/Silkscreen Top")
		(7 "B.SilkS" user "Ref Des/Silkscreen Bottom")
		(1 "F.Mask" user "Board Geometry/Soldermask Top")
		(3 "B.Mask" user "Board Geometry/Soldermask Bottom")
		(17 "Dwgs.User" user "User.Drawings")
		(19 "Cmts.User" user "User.Comments")
		(21 "Eco1.User" user "User.Eco1")
		(23 "Eco2.User" user "User.Eco2")
		(25 "Edge.Cuts" user "Board Geometry/Outline")
		(27 "Margin" user)
		(31 "F.CrtYd" user "Package Geometry/Place Bound Top")
		(29 "B.CrtYd" user "Package Geometry/Place Bound Bottom")
		(35 "F.Fab" user "Ref Des/Assembly Top")
		(33 "B.Fab" user "Ref Des/Assembly Bottom")
	)
	(footprint ""
		(layer "B.Cu")
		(at 101.385878 -144.63141 180)
		(property "Reference" "PC253"
			(at 0 0 0)
			(layer "B.SilkS")
			(hide yes)
			(effects
				(font
					(size 1.27 1.27)
				)
				(justify mirror)
			)
		)
		(property "Value" ""
			(at 0 0 0)
			(layer "B.Fab")
			(effects
				(font
					(size 1.27 1.27)
				)
				(justify mirror)
			)
		)
		(duplicate_pad_numbers_are_jumpers no)
		(fp_line
			(start 0.7874 0.4064)
			(end 0.7874 -0.4064)
			(stroke
				(width 0.1524)
				(type default)
			)
			(layer "B.SilkS")
		)
		(fp_line
			(start 0.7874 -0.4064)
			(end -0.7874 -0.4064)
			(stroke
				(width 0.1524)
				(type default)
			)
			(layer "B.SilkS")
		)
		(fp_line
			(start -0.7874 0.4064)
			(end 0.7874 0.4064)
			(stroke
				(width 0.1524)
				(type default)
			)
			(layer "B.SilkS")
		)
		(fp_line
			(start -0.7874 -0.4064)
			(end -0.7874 0.4064)
			(stroke
				(width 0.1524)
				(type default)
			)
			(layer "B.SilkS")
		)
		(fp_line
			(start 0.67945 0.3048)
			(end 0.67945 -0.305054)
			(stroke
				(width 0.1)
				(type default)
			)
			(layer "B.Fab")
		)
		(fp_line
			(start 0.67945 -0.305054)
			(end 0.12065 -0.305054)
			(stroke
				(width 0.1)
				(type default)
			)
			(layer "B.Fab")
		)
		(fp_line
			(start 0.12065 0.3048)
			(end 0.67945 0.3048)
			(stroke
				(width 0.1)
				(type default)
			)
			(layer "B.Fab")
		)
		(fp_line
			(start 0.12065 0.2794)
			(end 0.12065 0.3048)
			(stroke
				(width 0.1)
				(type default)
			)
			(layer "B.Fab")
		)
		(fp_line
			(start 0.12065 -0.2794)
			(end -0.12065 -0.2794)
			(stroke
				(width 0.1)
				(type default)
			)
			(layer "B.Fab")
		)
		(fp_line
			(start 0.12065 -0.305054)
			(end 0.12065 -0.2794)
			(stroke
				(width 0.1)
				(type default)
			)
			(layer "B.Fab")
		)
		(fp_line
			(start -0.120396 0.3048)
			(end -0.120396 0.2794)
			(stroke
				(width 0.1)
				(type default)
			)
			(layer "B.Fab")
		)
		(fp_line
			(start -0.120396 0.2794)
			(end 0.12065 0.2794)
			(stroke
				(width 0.1)
				(type default)
			)
			(layer "B.Fab")
		)
		(fp_line
			(start -0.12065 -0.2794)
			(end -0.12065 -0.3048)
			(stroke
				(width 0.1)
				(type default)
			)
			(layer "B.Fab")
		)
		(fp_line
			(start -0.12065 -0.3048)
			(end -0.67945 -0.3048)
			(stroke
				(width 0.1)
				(type default)
			)
			(layer "B.Fab")
		)
		(fp_line
			(start -0.67945 0.3048)
			(end -0.120396 0.3048)
			(stroke
				(width 0.1)
				(type default)
			)
			(layer "B.Fab")
		)
		(fp_line
			(start -0.67945 -0.3048)
			(end -0.67945 0.3048)
			(stroke
				(width 0.1)
				(type default)
			)
			(layer "B.Fab")
		)
		(pad "1" smd circle
			(at 0.40005 0)
			(size 0 0)
			(layers "B.Cu" "B.Mask" "B.Paste")
			(net "PVDDCR_SOC_P1_TEMP1")
		)
		(pad "2" smd circle
			(at -0.40005 0)
			(size 0 0)
			(layers "B.Cu" "B.Mask" "B.Paste")
			(net "GND")
		)
	)
)
